(kicad_pcb
	(version 20260206)
	(generator "pcbnew")
	(generator_version "10.0")
	(general
		(thickness 1.6)
		(legacy_teardrops no)
	)
	(paper "A4")
	(title_block
		(title "v1-chassis-manager — T6M_CM_d_v01_1031_1645.brd")
		(comment 1 "Open CloudServer (Microsoft) / footprints 296-305 of 2512")
	)
	(layers
		(0 "F.Cu" signal "TOP")
		(4 "In1.Cu" signal "GND1")
		(6 "In2.Cu" signal "IN1")
		(8 "In3.Cu" signal "VCC1")
		(10 "In4.Cu" signal "VCC2")
		(12 "In5.Cu" signal "GND2")
		(14 "In6.Cu" signal "IN2")
		(16 "In7.Cu" signal "IN3")
		(18 "In8.Cu" signal "GND3")
		(2 "B.Cu" signal "BOTTOM")
		(9 "F.Adhes" user "F.Adhesive")
		(11 "B.Adhes" user "B.Adhesive")
		(13 "F.Paste" user "Package Geometry/Pastemask Top")
		(15 "B.Paste" user "Package Geometry/Pastemask Bottom")
		(5 "F.SilkS" user "Ref Des/Silkscreen Top")
		(7 "B.SilkS" user "Ref Des/Silkscreen Bottom")
		(1 "F.Mask" user "Board Geometry/Soldermask Top")
		(3 "B.Mask" user "Board Geometry/Soldermask Bottom")
		(17 "Dwgs.User" user "User.Drawings")
		(19 "Cmts.User" user "User.Comments")
		(21 "Eco1.User" user "User.Eco1")
		(23 "Eco2.User" user "User.Eco2")
		(25 "Edge.Cuts" user "Board Geometry/Outline")
		(27 "Margin" user)
		(31 "F.CrtYd" user "Package Geometry/Place Bound Top")
		(29 "B.CrtYd" user "Package Geometry/Place Bound Bottom")
		(35 "F.Fab" user "Ref Des/Assembly Top")
		(33 "B.Fab" user "Ref Des/Assembly Bottom")
	)
	(footprint ""
		(layer "F.Cu")
		(at 16.825468 -54.773322 90)
		(property "Reference" "L39"
			(at -1.449578 14.098016 90)
			(unlocked yes)
			(layer "F.SilkS")
			(effects
				(font
					(size 0.7874 0.5842)
					(thickness 0.1524)
				)
			)
		)
		(property "Value" ""
			(at 0 0 90)
			(layer "F.Fab")
			(effects
				(font
					(size 1.27 1.27)
				)
			)
		)
		(duplicate_pad_numbers_are_jumpers no)
		(fp_line
			(start 1.2954 -0.635)
			(end 1.2954 0.635)
			(stroke
				(width 0.1524)
				(type default)
			)
			(layer "F.SilkS")
		)
		(fp_line
			(start -1.2954 -0.635)
			(end 1.2954 -0.635)
			(stroke
				(width 0.1524)
				(type default)
			)
			(layer "F.SilkS")
		)
		(fp_line
			(start -1.2954 -0.635)
			(end -1.2954 0.635)
			(stroke
				(width 0.1524)
				(type default)
			)
			(layer "F.SilkS")
		)
		(fp_line
			(start 0.127 -0.5842)
			(end 0.127 0.5842)
			(stroke
				(width 0.1524)
				(type default)
			)
			(layer "F.SilkS")
		)
		(fp_line
			(start -0.127 -0.5842)
			(end -0.127 0.5842)
			(stroke
				(width 0.1524)
				(type default)
			)
			(layer "F.SilkS")
		)
		(fp_line
			(start 1.2954 0.635)
			(end -1.2954 0.635)
			(stroke
				(width 0.1524)
				(type default)
			)
			(layer "F.SilkS")
		)
		(fp_poly
			(pts
				(xy -0.9144 0.508) (xy -0.9144 0.3556) (xy -1.143 0.3556) (xy -1.143 -0.3556) (xy -0.9144 -0.3556)
				(xy -0.9144 -0.508) (xy 0.9144 -0.508) (xy 0.9144 -0.3556) (xy 1.143 -0.3556) (xy 1.143 0.3556)
				(xy 0.9144 0.3556) (xy 0.9144 0.508)
			)
			(stroke
				(width 0)
				(type default)
			)
			(fill no)
			(layer "F.CrtYd")
		)
		(pad "1" smd rect
			(at 0.7366 0 180)
			(size 0.7112 0.8128)
			(layers "F.Cu" "F.Mask" "F.Paste")
			(net "BMC_NODE1_GFX_BLUE")
		)
		(pad "2" smd rect
			(at -0.7366 0 180)
			(size 0.7112 0.8128)
			(layers "F.Cu" "F.Mask" "F.Paste")
			(net "CRT_B_L")
		)
	)
	(footprint ""
		(layer "F.Cu")
		(at 190.627 -124.079)
		(property "Reference" "R1267"
			(at 1.27 0.02667 0)
			(unlocked yes)
			(layer "F.SilkS")
			(effects
				(font
					(size 0.7874 0.5842)
					(thickness 0.1524)
				)
				(justify left)
			)
		)
		(property "Value" ""
			(at 0 0 0)
			(layer "F.Fab")
			(effects
				(font
					(size 1.27 1.27)
				)
			)
		)
		(duplicate_pad_numbers_are_jumpers no)
		(fp_line
			(start -0.7874 -0.4064)
			(end 0.7874 -0.4064)
			(stroke
				(width 0.1524)
				(type default)
			)
			(layer "F.SilkS")
		)
		(fp_line
			(start -0.7874 0.4064)
			(end -0.7874 -0.4064)
			(stroke
				(width 0.1524)
				(type default)
			)
			(layer "F.SilkS")
		)
		(fp_line
			(start 0.7874 -0.4064)
			(end 0.7874 0.4064)
			(stroke
				(width 0.1524)
				(type default)
			)
			(layer "F.SilkS")
		)
		(fp_line
			(start 0.7874 0.4064)
			(end -0.7874 0.4064)
			(stroke
				(width 0.1524)
				(type default)
			)
			(layer "F.SilkS")
		)
		(fp_poly
			(pts
				(xy -0.508 0.2794) (xy -0.508 0.2286) (xy -0.635 0.2286) (xy -0.635 -0.254) (xy -0.5334 -0.254)
				(xy -0.5334 -0.2794) (xy 0.5334 -0.2794) (xy 0.5334 -0.254) (xy 0.635 -0.254) (xy 0.635 0.254) (xy 0.5334 0.254)
				(xy 0.5334 0.2794)
			)
			(stroke
				(width 0)
				(type default)
			)
			(fill no)
			(layer "F.CrtYd")
		)
		(pad "1" smd rect
			(at 0.40005 0)
			(size 0.4572 0.508)
			(layers "F.Cu" "F.Mask" "F.Paste")
			(net "SIO_JTAG_CPLD1_TCK_R")
		)
		(pad "2" smd rect
			(at -0.40005 0)
			(size 0.4572 0.508)
			(layers "F.Cu" "F.Mask" "F.Paste")
			(net "SIO_JTAG_CPLD1_TCK")
		)
	)
	(footprint ""
		(layer "F.Cu")
		(at 79.984092 -75.146154 180)
		(property "Reference" "R114"
			(at 0.336296 -16.257524 0)
			(unlocked yes)
			(layer "F.SilkS")
			(effects
				(font
					(size 0.7874 0.5842)
					(thickness 0.1524)
				)
				(justify left)
			)
		)
		(property "Value" ""
			(at 0 0 180)
			(layer "F.Fab")
			(effects
				(font
					(size 1.27 1.27)
				)
			)
		)
		(duplicate_pad_numbers_are_jumpers no)
		(fp_line
			(start 0.7874 0.4064)
			(end -0.7874 0.4064)
			(stroke
				(width 0.1524)
				(type default)
			)
			(layer "F.SilkS")
		)
		(fp_line
			(start 0.7874 -0.4064)
			(end 0.7874 0.4064)
			(stroke
				(width 0.1524)
				(type default)
			)
			(layer "F.SilkS")
		)
		(fp_line
			(start -0.7874 0.4064)
			(end -0.7874 -0.4064)
			(stroke
				(width 0.1524)
				(type default)
			)
			(layer "F.SilkS")
		)
		(fp_line
			(start -0.7874 -0.4064)
			(end 0.7874 -0.4064)
			(stroke
				(width 0.1524)
				(type default)
			)
			(layer "F.SilkS")
		)
		(fp_poly
			(pts
				(xy -0.508 0.2794) (xy -0.508 0.2286) (xy -0.635 0.2286) (xy -0.635 -0.254) (xy -0.5334 -0.254)
				(xy -0.5334 -0.2794) (xy 0.5334 -0.2794) (xy 0.5334 -0.254) (xy 0.635 -0.254) (xy 0.635 0.254) (xy 0.5334 0.254)
				(xy 0.5334 0.2794)
			)
			(stroke
				(width 0)
				(type default)
			)
			(fill no)
			(layer "F.CrtYd")
		)
		(pad "1" smd rect
			(at 0.40005 0 180)
			(size 0.4572 0.508)
			(layers "F.Cu" "F.Mask" "F.Paste")
			(net "XDP_CPU_NODE1_PRDY_L")
		)
		(pad "2" smd rect
			(at -0.40005 0 180)
			(size 0.4572 0.508)
			(layers "F.Cu" "F.Mask" "F.Paste")
			(net "P1V05_NODE1")
		)
	)
	(footprint ""
		(layer "F.Cu")
		(at 172.701458 -12.474194 90)
		(property "Reference" "R1212"
			(at -0.981202 2.105152 90)
			(unlocked yes)
			(layer "F.SilkS")
			(effects
				(font
					(size 0.7874 0.5842)
					(thickness 0.1524)
				)
				(justify left)
			)
		)
		(property "Value" ""
			(at 0 0 90)
			(layer "F.Fab")
			(effects
				(font
					(size 1.27 1.27)
				)
			)
		)
		(duplicate_pad_numbers_are_jumpers no)
		(fp_line
			(start 0.7874 -0.4064)
			(end 0.7874 0.4064)
			(stroke
				(width 0.1524)
				(type default)
			)
			(layer "F.SilkS")
		)
		(fp_line
			(start -0.7874 -0.4064)
			(end 0.7874 -0.4064)
			(stroke
				(width 0.1524)
				(type default)
			)
			(layer "F.SilkS")
		)
		(fp_line
			(start 0.7874 0.4064)
			(end -0.7874 0.4064)
			(stroke
				(width 0.1524)
				(type default)
			)
			(layer "F.SilkS")
		)
		(fp_line
			(start -0.7874 0.4064)
			(end -0.7874 -0.4064)
			(stroke
				(width 0.1524)
				(type default)
			)
			(layer "F.SilkS")
		)
		(fp_poly
			(pts
				(xy -0.508 0.2794) (xy -0.508 0.2286) (xy -0.635 0.2286) (xy -0.635 -0.254) (xy -0.5334 -0.254)
				(xy -0.5334 -0.2794) (xy 0.5334 -0.2794) (xy 0.5334 -0.254) (xy 0.635 -0.254) (xy 0.635 0.254) (xy 0.5334 0.254)
				(xy 0.5334 0.2794)
			)
			(stroke
				(width 0)
				(type default)
			)
			(fill no)
			(layer "F.CrtYd")
		)
		(pad "1" smd rect
			(at 0.40005 0 90)
			(size 0.4572 0.508)
			(layers "F.Cu" "F.Mask" "F.Paste")
			(net "GND")
		)
		(pad "2" smd rect
			(at -0.40005 0 90)
			(size 0.4572 0.508)
			(layers "F.Cu" "F.Mask" "F.Paste")
			(net "JTAG_CPLD3_TCK")
		)
	)
	(footprint ""
		(layer "F.Cu")
		(at 136.822688 -64.480948 180)
		(property "Reference" "C329"
			(at 2.02565 0.37719 90)
			(unlocked yes)
			(layer "F.SilkS")
			(effects
				(font
					(size 0.7874 0.5842)
					(thickness 0.1524)
				)
			)
		)
		(property "Value" ""
			(at 0 0 180)
			(layer "F.Fab")
			(effects
				(font
					(size 1.27 1.27)
				)
			)
		)
		(duplicate_pad_numbers_are_jumpers no)
		(fp_line
			(start 1.2954 0.5842)
			(end -1.2954 0.5842)
			(stroke
				(width 0.1524)
				(type default)
			)
			(layer "F.SilkS")
		)
		(fp_line
			(start 1.2954 -0.5842)
			(end 1.2954 0.5842)
			(stroke
				(width 0.1524)
				(type default)
			)
			(layer "F.SilkS")
		)
		(fp_line
			(start 0 -0.5842)
			(end 0 0.5842)
			(stroke
				(width 0.1524)
				(type default)
			)
			(layer "F.SilkS")
		)
		(fp_line
			(start -1.2954 0.5842)
			(end -1.2954 -0.5842)
			(stroke
				(width 0.1524)
				(type default)
			)
			(layer "F.SilkS")
		)
		(fp_line
			(start -1.2954 -0.5842)
			(end 1.2954 -0.5842)
			(stroke
				(width 0.1524)
				(type default)
			)
			(layer "F.SilkS")
		)
		(fp_poly
			(pts
				(xy 0.8636 -0.4572) (xy 0.8636 -0.3556) (xy 1.143 -0.3556) (xy 1.143 0.3556) (xy 0.8636 0.3556)
				(xy 0.8636 0.4572) (xy -0.8636 0.4572) (xy -0.8636 0.3556) (xy -1.143 0.3556) (xy -1.143 -0.3556)
				(xy -0.8636 -0.3556) (xy -0.8636 -0.4572)
			)
			(stroke
				(width 0)
				(type default)
			)
			(fill no)
			(layer "F.CrtYd")
		)
		(fp_line
			(start 0.884936 0.504952)
			(end -0.884936 0.504952)
			(stroke
				(width 0.1)
				(type default)
			)
			(layer "F.Fab")
		)
		(fp_line
			(start 0.884936 -0.504952)
			(end 0.884936 0.504952)
			(stroke
				(width 0.1)
				(type default)
			)
			(layer "F.Fab")
		)
		(fp_line
			(start -0.884936 0.504952)
			(end -0.884936 -0.504952)
			(stroke
				(width 0.1)
				(type default)
			)
			(layer "F.Fab")
		)
		(fp_line
			(start -0.884936 -0.504952)
			(end 0.884936 -0.504952)
			(stroke
				(width 0.1)
				(type default)
			)
			(layer "F.Fab")
		)
		(pad "1" smd rect
			(at 0.7366 0 270)
			(size 0.7112 0.8128)
			(layers "F.Cu" "F.Mask" "F.Paste")
			(net "P1V8_NODE1")
		)
		(pad "2" smd rect
			(at -0.7366 0 270)
			(size 0.7112 0.8128)
			(layers "F.Cu" "F.Mask" "F.Paste")
			(net "GND")
		)
	)
	(footprint ""
		(layer "F.Cu")
		(at 138.303 -51.435 90)
		(property "Reference" "R777"
			(at 16.383 30.70987 90)
			(unlocked yes)
			(layer "F.SilkS")
			(effects
				(font
					(size 0.7874 0.5842)
					(thickness 0.1524)
				)
				(justify left)
			)
		)
		(property "Value" ""
			(at 0 0 90)
			(layer "F.Fab")
			(effects
				(font
					(size 1.27 1.27)
				)
			)
		)
		(duplicate_pad_numbers_are_jumpers no)
		(fp_line
			(start 0.7874 -0.4064)
			(end 0.7874 0.4064)
			(stroke
				(width 0.1524)
				(type default)
			)
			(layer "F.SilkS")
		)
		(fp_line
			(start -0.7874 -0.4064)
			(end 0.7874 -0.4064)
			(stroke
				(width 0.1524)
				(type default)
			)
			(layer "F.SilkS")
		)
		(fp_line
			(start 0.7874 0.4064)
			(end -0.7874 0.4064)
			(stroke
				(width 0.1524)
				(type default)
			)
			(layer "F.SilkS")
		)
		(fp_line
			(start -0.7874 0.4064)
			(end -0.7874 -0.4064)
			(stroke
				(width 0.1524)
				(type default)
			)
			(layer "F.SilkS")
		)
		(fp_poly
			(pts
				(xy -0.508 0.2794) (xy -0.508 0.2286) (xy -0.635 0.2286) (xy -0.635 -0.254) (xy -0.5334 -0.254)
				(xy -0.5334 -0.2794) (xy 0.5334 -0.2794) (xy 0.5334 -0.254) (xy 0.635 -0.254) (xy 0.635 0.254) (xy 0.5334 0.254)
				(xy 0.5334 0.2794)
			)
			(stroke
				(width 0)
				(type default)
			)
			(fill no)
			(layer "F.CrtYd")
		)
		(pad "1" smd rect
			(at 0.40005 0 90)
			(size 0.4572 0.508)
			(layers "F.Cu" "F.Mask" "F.Paste")
			(net "P5V_NODE1")
		)
		(pad "2" smd rect
			(at -0.40005 0 90)
			(size 0.4572 0.508)
			(layers "F.Cu" "F.Mask" "F.Paste")
			(net "UART_CTS_P3_N")
		)
	)
	(footprint ""
		(layer "F.Cu")
		(at 24.752046 -47.095664 180)
		(property "Reference" "Q18"
			(at -2.273046 0.212852 90)
			(unlocked yes)
			(layer "F.SilkS")
			(effects
				(font
					(size 0.7874 0.5842)
					(thickness 0.1524)
				)
			)
		)
		(property "Value" ""
			(at 0 0 180)
			(layer "F.Fab")
			(effects
				(font
					(size 1.27 1.27)
				)
			)
		)
		(duplicate_pad_numbers_are_jumpers no)
		(fp_line
			(start 1.651 1.905)
			(end -1.651 1.905)
			(stroke
				(width 0.1524)
				(type default)
			)
			(layer "F.SilkS")
		)
		(fp_line
			(start 1.651 -1.905)
			(end 1.651 1.905)
			(stroke
				(width 0.1524)
				(type default)
			)
			(layer "F.SilkS")
		)
		(fp_line
			(start -1.651 1.905)
			(end -1.651 -1.905)
			(stroke
				(width 0.1524)
				(type default)
			)
			(layer "F.SilkS")
		)
		(fp_line
			(start -1.651 -1.905)
			(end 1.651 -1.905)
			(stroke
				(width 0.1524)
				(type default)
			)
			(layer "F.SilkS")
		)
		(fp_poly
			(pts
				(xy -1.524 0.7112) (xy -1.524 1.7526) (xy -0.508 1.7526) (xy -0.508 0.6985) (xy 0.508 0.6985) (xy 0.508 1.7526)
				(xy 1.524 1.7526) (xy 1.524 0.6985) (xy 1.524 -0.6985) (xy 0.508 -0.6985) (xy 0.508 -1.7526) (xy -0.508 -1.7526)
				(xy -0.508 -0.6985) (xy -1.524 -0.6985) (xy -1.524 0.6985)
			)
			(stroke
				(width 0)
				(type default)
			)
			(fill no)
			(layer "F.CrtYd")
		)
		(fp_text user "S"
			(at 0.446278 2.465324 0)
			(unlocked yes)
			(layer "F.SilkS")
			(effects
				(font
					(size 0.635 0.4064)
					(thickness 0.1524)
				)
			)
		)
		(fp_text user "D"
			(at -2.043176 -1.641602 0)
			(unlocked yes)
			(layer "F.SilkS")
			(effects
				(font
					(size 0.635 0.4064)
					(thickness 0.1524)
				)
			)
		)
		(fp_text user "G"
			(at -2.293112 2.310892 0)
			(unlocked yes)
			(layer "F.SilkS")
			(effects
				(font
					(size 0.635 0.4064)
					(thickness 0.1524)
				)
			)
		)
		(pad "D" smd rect
			(at 0 -1.1176 180)
			(size 1.016 1.27)
			(layers "F.Cu" "F.Mask" "F.Paste")
			(net "I2C_VIDREAR_5V_SDA")
		)
		(pad "G" smd rect
			(at -1.016 1.1176 180)
			(size 1.016 1.27)
			(layers "F.Cu" "F.Mask" "F.Paste")
			(net "N21581283")
		)
		(pad "S" smd rect
			(at 1.016 1.1176 180)
			(size 1.016 1.27)
			(layers "F.Cu" "F.Mask" "F.Paste")
			(net "SMB_BMC_NODE1_DDC_DAT")
		)
	)
	(footprint ""
		(layer "F.Cu")
		(at 73.39076 -188.126624 -90)
		(property "Reference" "R944"
			(at -4.548886 1.038098 90)
			(unlocked yes)
			(layer "F.SilkS")
			(effects
				(font
					(size 0.7874 0.5842)
					(thickness 0.1524)
				)
				(justify left)
			)
		)
		(property "Value" ""
			(at 0 0 270)
			(layer "F.Fab")
			(effects
				(font
					(size 1.27 1.27)
				)
			)
		)
		(duplicate_pad_numbers_are_jumpers no)
		(fp_line
			(start -0.7874 0.4064)
			(end -0.7874 -0.4064)
			(stroke
				(width 0.1524)
				(type default)
			)
			(layer "F.SilkS")
		)
		(fp_line
			(start 0.7874 0.4064)
			(end -0.7874 0.4064)
			(stroke
				(width 0.1524)
				(type default)
			)
			(layer "F.SilkS")
		)
		(fp_line
			(start -0.7874 -0.4064)
			(end 0.7874 -0.4064)
			(stroke
				(width 0.1524)
				(type default)
			)
			(layer "F.SilkS")
		)
		(fp_line
			(start 0.7874 -0.4064)
			(end 0.7874 0.4064)
			(stroke
				(width 0.1524)
				(type default)
			)
			(layer "F.SilkS")
		)
		(fp_poly
			(pts
				(xy -0.508 0.2794) (xy -0.508 0.2286) (xy -0.635 0.2286) (xy -0.635 -0.254) (xy -0.5334 -0.254)
				(xy -0.5334 -0.2794) (xy 0.5334 -0.2794) (xy 0.5334 -0.254) (xy 0.635 -0.254) (xy 0.635 0.254) (xy 0.5334 0.254)
				(xy 0.5334 0.2794)
			)
			(stroke
				(width 0)
				(type default)
			)
			(fill no)
			(layer "F.CrtYd")
		)
		(pad "1" smd rect
			(at 0.40005 0 270)
			(size 0.4572 0.508)
			(layers "F.Cu" "F.Mask" "F.Paste")
			(net "UART_T4_NODE3_RXD")
		)
		(pad "2" smd rect
			(at -0.40005 0 270)
			(size 0.4572 0.508)
			(layers "F.Cu" "F.Mask" "F.Paste")
			(net "UART_T4_NODE3_RXD_R")
		)
	)
	(footprint ""
		(layer "F.Cu")
		(at 44.53509 -4.187952 90)
		(property "Reference" "PC71"
			(at -3.608324 -13.705586 90)
			(unlocked yes)
			(layer "F.SilkS")
			(effects
				(font
					(size 0.7874 0.5842)
					(thickness 0.1524)
				)
				(justify left)
			)
		)
		(property "Value" ""
			(at 0 0 90)
			(layer "F.Fab")
			(effects
				(font
					(size 1.27 1.27)
				)
			)
		)
		(duplicate_pad_numbers_are_jumpers no)
		(fp_line
			(start 0.7874 -0.4064)
			(end 0.7874 0.4064)
			(stroke
				(width 0.1524)
				(type default)
			)
			(layer "F.SilkS")
		)
		(fp_line
			(start -0.7874 -0.4064)
			(end 0.7874 -0.4064)
			(stroke
				(width 0.1524)
				(type default)
			)
			(layer "F.SilkS")
		)
		(fp_line
			(start 0 0.381)
			(end 0 -0.381)
			(stroke
				(width 0.1524)
				(type default)
			)
			(layer "F.SilkS")
		)
		(fp_line
			(start 0.7874 0.4064)
			(end -0.7874 0.4064)
			(stroke
				(width 0.1524)
				(type default)
			)
			(layer "F.SilkS")
		)
		(fp_line
			(start -0.7874 0.4064)
			(end -0.7874 -0.4064)
			(stroke
				(width 0.1524)
				(type default)
			)
			(layer "F.SilkS")
		)
		(fp_poly
			(pts
				(xy -0.5334 0.254) (xy -0.635 0.254) (xy -0.635 0.2286) (xy -0.635 -0.254) (xy -0.5334 -0.254) (xy -0.5334 -0.2794)
				(xy 0.5334 -0.2794) (xy 0.5334 -0.254) (xy 0.635 -0.254) (xy 0.635 0.254) (xy 0.5334 0.254) (xy 0.5334 0.2794)
				(xy -0.508 0.2794) (xy -0.5334 0.2794)
			)
			(stroke
				(width 0)
				(type default)
			)
			(fill no)
			(layer "F.CrtYd")
		)
		(pad "1" smd rect
			(at 0.40005 0 90)
			(size 0.4572 0.508)
			(layers "F.Cu" "F.Mask" "F.Paste")
			(net "SW_PV_VDDR_NODE1_VIN_FLT")
		)
		(pad "2" smd rect
			(at -0.40005 0 90)
			(size 0.4572 0.508)
			(layers "F.Cu" "F.Mask" "F.Paste")
			(net "GND")
		)
	)
	(footprint ""
		(layer "F.Cu")
		(at 49.88814 -163.89985 90)
		(property "Reference" "R540"
			(at -131.03606 -3.589528 90)
			(unlocked yes)
			(layer "F.SilkS")
			(effects
				(font
					(size 0.7874 0.5842)
					(thickness 0.1524)
				)
				(justify left)
			)
		)
		(property "Value" ""
			(at 0 0 90)
			(layer "F.Fab")
			(effects
				(font
					(size 1.27 1.27)
				)
			)
		)
		(duplicate_pad_numbers_are_jumpers no)
		(fp_line
			(start 0.7874 -0.4064)
			(end 0.7874 0.4064)
			(stroke
				(width 0.1524)
				(type default)
			)
			(layer "F.SilkS")
		)
		(fp_line
			(start -0.7874 -0.4064)
			(end 0.7874 -0.4064)
			(stroke
				(width 0.1524)
				(type default)
			)
			(layer "F.SilkS")
		)
		(fp_line
			(start 0.7874 0.4064)
			(end -0.7874 0.4064)
			(stroke
				(width 0.1524)
				(type default)
			)
			(layer "F.SilkS")
		)
		(fp_line
			(start -0.7874 0.4064)
			(end -0.7874 -0.4064)
			(stroke
				(width 0.1524)
				(type default)
			)
			(layer "F.SilkS")
		)
		(fp_poly
			(pts
				(xy -0.508 0.2794) (xy -0.508 0.2286) (xy -0.635 0.2286) (xy -0.635 -0.254) (xy -0.5334 -0.254)
				(xy -0.5334 -0.2794) (xy 0.5334 -0.2794) (xy 0.5334 -0.254) (xy 0.635 -0.254) (xy 0.635 0.254) (xy 0.5334 0.254)
				(xy 0.5334 0.2794)
			)
			(stroke
				(width 0)
				(type default)
			)
			(fill no)
			(layer "F.CrtYd")
		)
		(pad "1" smd rect
			(at 0.40005 0 90)
			(size 0.4572 0.508)
			(layers "F.Cu" "F.Mask" "F.Paste")
			(net "P3V3_NODE1")
		)
		(pad "2" smd rect
			(at -0.40005 0 90)
			(size 0.4572 0.508)
			(layers "F.Cu" "F.Mask" "F.Paste")
			(net "SMB_LAN1_DAT")
		)
	)
)
